(kicad_pcb
	(version 20260206)
	(generator "pcbnew")
	(generator_version "10.0")
	(general
		(thickness 1.6)
		(legacy_teardrops no)
	)
	(paper "A4")
	(title_block
		(title "v1-chassis-manager — T6M_CM_d_v01_1031_1645.brd")
		(comment 1 "Open CloudServer (Microsoft) / footprints 616-624 of 2512")
	)
	(layers
		(0 "F.Cu" signal "TOP")
		(4 "In1.Cu" signal "GND1")
		(6 "In2.Cu" signal "IN1")
		(8 "In3.Cu" signal "VCC1")
		(10 "In4.Cu" signal "VCC2")
		(12 "In5.Cu" signal "GND2")
		(14 "In6.Cu" signal "IN2")
		(16 "In7.Cu" signal "IN3")
		(18 "In8.Cu" signal "GND3")
		(2 "B.Cu" signal "BOTTOM")
		(9 "F.Adhes" user "F.Adhesive")
		(11 "B.Adhes" user "B.Adhesive")
		(13 "F.Paste" user "Package Geometry/Pastemask Top")
		(15 "B.Paste" user "Package Geometry/Pastemask Bottom")
		(5 "F.SilkS" user "Ref Des/Silkscreen Top")
		(7 "B.SilkS" user "Ref Des/Silkscreen Bottom")
		(1 "F.Mask" user "Board Geometry/Soldermask Top")
		(3 "B.Mask" user "Board Geometry/Soldermask Bottom")
		(17 "Dwgs.User" user "User.Drawings")
		(19 "Cmts.User" user "User.Comments")
		(21 "Eco1.User" user "User.Eco1")
		(23 "Eco2.User" user "User.Eco2")
		(25 "Edge.Cuts" user "Board Geometry/Outline")
		(27 "Margin" user)
		(31 "F.CrtYd" user "Package Geometry/Place Bound Top")
		(29 "B.CrtYd" user "Package Geometry/Place Bound Bottom")
		(35 "F.Fab" user "Ref Des/Assembly Top")
		(33 "B.Fab" user "Ref Des/Assembly Bottom")
	)
	(footprint ""
		(layer "F.Cu")
		(at 60.81776 -185.205624 -90)
		(property "Reference" "R940"
			(at -4.006088 0.474218 90)
			(unlocked yes)
			(layer "F.SilkS")
			(effects
				(font
					(size 0.7874 0.5842)
					(thickness 0.1524)
				)
				(justify left)
			)
		)
		(property "Value" ""
			(at 0 0 270)
			(layer "F.Fab")
			(effects
				(font
					(size 1.27 1.27)
				)
			)
		)
		(duplicate_pad_numbers_are_jumpers no)
		(fp_line
			(start -0.7874 0.4064)
			(end -0.7874 -0.4064)
			(stroke
				(width 0.1524)
				(type default)
			)
			(layer "F.SilkS")
		)
		(fp_line
			(start 0.7874 0.4064)
			(end -0.7874 0.4064)
			(stroke
				(width 0.1524)
				(type default)
			)
			(layer "F.SilkS")
		)
		(fp_line
			(start -0.7874 -0.4064)
			(end 0.7874 -0.4064)
			(stroke
				(width 0.1524)
				(type default)
			)
			(layer "F.SilkS")
		)
		(fp_line
			(start 0.7874 -0.4064)
			(end 0.7874 0.4064)
			(stroke
				(width 0.1524)
				(type default)
			)
			(layer "F.SilkS")
		)
		(fp_poly
			(pts
				(xy -0.508 0.2794) (xy -0.508 0.2286) (xy -0.635 0.2286) (xy -0.635 -0.254) (xy -0.5334 -0.254)
				(xy -0.5334 -0.2794) (xy 0.5334 -0.2794) (xy 0.5334 -0.254) (xy 0.635 -0.254) (xy 0.635 0.254) (xy 0.5334 0.254)
				(xy 0.5334 0.2794)
			)
			(stroke
				(width 0)
				(type default)
			)
			(fill no)
			(layer "F.CrtYd")
		)
		(pad "1" smd rect
			(at 0.40005 0 270)
			(size 0.4572 0.508)
			(layers "F.Cu" "F.Mask" "F.Paste")
			(net "UART_T2_NODE2_TXD")
		)
		(pad "2" smd rect
			(at -0.40005 0 270)
			(size 0.4572 0.508)
			(layers "F.Cu" "F.Mask" "F.Paste")
			(net "UART_T2_NODE2_TXD_R")
		)
	)
	(footprint ""
		(layer "F.Cu")
		(at 114.50066 -140.193776 -90)
		(property "Reference" "PC104"
			(at -4.119626 -3.345942 90)
			(unlocked yes)
			(layer "F.SilkS")
			(effects
				(font
					(size 0.635 0.4064)
					(thickness 0.1524)
				)
				(justify left)
			)
		)
		(property "Value" ""
			(at 0 0 270)
			(layer "F.Fab")
			(effects
				(font
					(size 1.27 1.27)
				)
			)
		)
		(duplicate_pad_numbers_are_jumpers no)
		(fp_line
			(start -0.7874 0.4064)
			(end -0.7874 -0.4064)
			(stroke
				(width 0.1524)
				(type default)
			)
			(layer "F.SilkS")
		)
		(fp_line
			(start 0.7874 0.4064)
			(end -0.7874 0.4064)
			(stroke
				(width 0.1524)
				(type default)
			)
			(layer "F.SilkS")
		)
		(fp_line
			(start 0 0.381)
			(end 0 -0.381)
			(stroke
				(width 0.1524)
				(type default)
			)
			(layer "F.SilkS")
		)
		(fp_line
			(start -0.7874 -0.4064)
			(end 0.7874 -0.4064)
			(stroke
				(width 0.1524)
				(type default)
			)
			(layer "F.SilkS")
		)
		(fp_line
			(start 0.7874 -0.4064)
			(end 0.7874 0.4064)
			(stroke
				(width 0.1524)
				(type default)
			)
			(layer "F.SilkS")
		)
		(fp_poly
			(pts
				(xy -0.5334 0.254) (xy -0.635 0.254) (xy -0.635 0.2286) (xy -0.635 -0.254) (xy -0.5334 -0.254) (xy -0.5334 -0.2794)
				(xy 0.5334 -0.2794) (xy 0.5334 -0.254) (xy 0.635 -0.254) (xy 0.635 0.254) (xy 0.5334 0.254) (xy 0.5334 0.2794)
				(xy -0.508 0.2794) (xy -0.5334 0.2794)
			)
			(stroke
				(width 0)
				(type default)
			)
			(fill no)
			(layer "F.CrtYd")
		)
		(pad "1" smd rect
			(at 0.40005 0 270)
			(size 0.4572 0.508)
			(layers "F.Cu" "F.Mask" "F.Paste")
			(net "VSENSE_VSS_CPU_NODE1")
		)
		(pad "2" smd rect
			(at -0.40005 0 270)
			(size 0.4572 0.508)
			(layers "F.Cu" "F.Mask" "F.Paste")
			(net "VSENSE_VCC_CPU_NODE1")
		)
	)
	(footprint ""
		(layer "F.Cu")
		(at 19.72564 -130.328416 180)
		(property "Reference" "PC62"
			(at -1.49352 0.232156 0)
			(unlocked yes)
			(layer "F.SilkS")
			(effects
				(font
					(size 0.7874 0.5842)
					(thickness 0.1524)
				)
				(justify left)
			)
		)
		(property "Value" ""
			(at 0 0 180)
			(layer "F.Fab")
			(effects
				(font
					(size 1.27 1.27)
				)
			)
		)
		(duplicate_pad_numbers_are_jumpers no)
		(fp_line
			(start 0.7874 0.4064)
			(end -0.7874 0.4064)
			(stroke
				(width 0.1524)
				(type default)
			)
			(layer "F.SilkS")
		)
		(fp_line
			(start 0.7874 -0.4064)
			(end 0.7874 0.4064)
			(stroke
				(width 0.1524)
				(type default)
			)
			(layer "F.SilkS")
		)
		(fp_line
			(start 0 0.381)
			(end 0 -0.381)
			(stroke
				(width 0.1524)
				(type default)
			)
			(layer "F.SilkS")
		)
		(fp_line
			(start -0.7874 0.4064)
			(end -0.7874 -0.4064)
			(stroke
				(width 0.1524)
				(type default)
			)
			(layer "F.SilkS")
		)
		(fp_line
			(start -0.7874 -0.4064)
			(end 0.7874 -0.4064)
			(stroke
				(width 0.1524)
				(type default)
			)
			(layer "F.SilkS")
		)
		(fp_poly
			(pts
				(xy -0.5334 0.254) (xy -0.635 0.254) (xy -0.635 0.2286) (xy -0.635 -0.254) (xy -0.5334 -0.254) (xy -0.5334 -0.2794)
				(xy 0.5334 -0.2794) (xy 0.5334 -0.254) (xy 0.635 -0.254) (xy 0.635 0.254) (xy 0.5334 0.254) (xy 0.5334 0.2794)
				(xy -0.508 0.2794) (xy -0.5334 0.2794)
			)
			(stroke
				(width 0)
				(type default)
			)
			(fill no)
			(layer "F.CrtYd")
		)
		(pad "1" smd rect
			(at 0.40005 0 180)
			(size 0.4572 0.508)
			(layers "F.Cu" "F.Mask" "F.Paste")
			(net "P1V05_NODE1_EN")
		)
		(pad "2" smd rect
			(at -0.40005 0 180)
			(size 0.4572 0.508)
			(layers "F.Cu" "F.Mask" "F.Paste")
			(net "GND")
		)
	)
	(footprint ""
		(layer "F.Cu")
		(at 94.234762 -183.799988 180)
		(property "Reference" "R902"
			(at 1.206246 7.182612 0)
			(unlocked yes)
			(layer "F.SilkS")
			(effects
				(font
					(size 0.7874 0.5842)
					(thickness 0.1524)
				)
				(justify left)
			)
		)
		(property "Value" ""
			(at 0 0 180)
			(layer "F.Fab")
			(effects
				(font
					(size 1.27 1.27)
				)
			)
		)
		(duplicate_pad_numbers_are_jumpers no)
		(fp_line
			(start 0.7874 0.4064)
			(end -0.7874 0.4064)
			(stroke
				(width 0.1524)
				(type default)
			)
			(layer "F.SilkS")
		)
		(fp_line
			(start 0.7874 -0.4064)
			(end 0.7874 0.4064)
			(stroke
				(width 0.1524)
				(type default)
			)
			(layer "F.SilkS")
		)
		(fp_line
			(start -0.7874 0.4064)
			(end -0.7874 -0.4064)
			(stroke
				(width 0.1524)
				(type default)
			)
			(layer "F.SilkS")
		)
		(fp_line
			(start -0.7874 -0.4064)
			(end 0.7874 -0.4064)
			(stroke
				(width 0.1524)
				(type default)
			)
			(layer "F.SilkS")
		)
		(fp_poly
			(pts
				(xy -0.508 0.2794) (xy -0.508 0.2286) (xy -0.635 0.2286) (xy -0.635 -0.254) (xy -0.5334 -0.254)
				(xy -0.5334 -0.2794) (xy 0.5334 -0.2794) (xy 0.5334 -0.254) (xy 0.635 -0.254) (xy 0.635 0.254) (xy 0.5334 0.254)
				(xy 0.5334 0.2794)
			)
			(stroke
				(width 0)
				(type default)
			)
			(fill no)
			(layer "F.CrtYd")
		)
		(pad "1" smd rect
			(at 0.40005 0 180)
			(size 0.4572 0.508)
			(layers "F.Cu" "F.Mask" "F.Paste")
			(net "T5_NODE3_EN")
		)
		(pad "2" smd rect
			(at -0.40005 0 180)
			(size 0.4572 0.508)
			(layers "F.Cu" "F.Mask" "F.Paste")
			(net "T5_NODE3_EN_R")
		)
	)
	(footprint ""
		(layer "F.Cu")
		(at 40.24122 -145.83029 -90)
		(property "Reference" "R557"
			(at 0.886968 6.618732 90)
			(unlocked yes)
			(layer "F.SilkS")
			(effects
				(font
					(size 0.7874 0.5842)
					(thickness 0.1524)
				)
				(justify left)
			)
		)
		(property "Value" ""
			(at 0 0 270)
			(layer "F.Fab")
			(effects
				(font
					(size 1.27 1.27)
				)
			)
		)
		(duplicate_pad_numbers_are_jumpers no)
		(fp_line
			(start -0.7874 0.4064)
			(end -0.7874 -0.4064)
			(stroke
				(width 0.1524)
				(type default)
			)
			(layer "F.SilkS")
		)
		(fp_line
			(start 0.7874 0.4064)
			(end -0.7874 0.4064)
			(stroke
				(width 0.1524)
				(type default)
			)
			(layer "F.SilkS")
		)
		(fp_line
			(start -0.7874 -0.4064)
			(end 0.7874 -0.4064)
			(stroke
				(width 0.1524)
				(type default)
			)
			(layer "F.SilkS")
		)
		(fp_line
			(start 0.7874 -0.4064)
			(end 0.7874 0.4064)
			(stroke
				(width 0.1524)
				(type default)
			)
			(layer "F.SilkS")
		)
		(fp_poly
			(pts
				(xy -0.508 0.2794) (xy -0.508 0.2286) (xy -0.635 0.2286) (xy -0.635 -0.254) (xy -0.5334 -0.254)
				(xy -0.5334 -0.2794) (xy 0.5334 -0.2794) (xy 0.5334 -0.254) (xy 0.635 -0.254) (xy 0.635 0.254) (xy 0.5334 0.254)
				(xy 0.5334 0.2794)
			)
			(stroke
				(width 0)
				(type default)
			)
			(fill no)
			(layer "F.CrtYd")
		)
		(pad "1" smd rect
			(at 0.40005 0 270)
			(size 0.4572 0.508)
			(layers "F.Cu" "F.Mask" "F.Paste")
			(net "GND")
		)
		(pad "2" smd rect
			(at -0.40005 0 270)
			(size 0.4572 0.508)
			(layers "F.Cu" "F.Mask" "F.Paste")
			(net "LAN1_NC_SI_CRS_DV")
		)
	)
	(footprint ""
		(layer "F.Cu")
		(at 71.706486 -148.476462 90)
		(property "Reference" "R298"
			(at 1.233932 -0.176784 90)
			(unlocked yes)
			(layer "F.SilkS")
			(effects
				(font
					(size 0.7874 0.5842)
					(thickness 0.1524)
				)
				(justify left)
			)
		)
		(property "Value" ""
			(at 0 0 90)
			(layer "F.Fab")
			(effects
				(font
					(size 1.27 1.27)
				)
			)
		)
		(duplicate_pad_numbers_are_jumpers no)
		(fp_line
			(start 0.7874 -0.4064)
			(end 0.7874 0.4064)
			(stroke
				(width 0.1524)
				(type default)
			)
			(layer "F.SilkS")
		)
		(fp_line
			(start -0.7874 -0.4064)
			(end 0.7874 -0.4064)
			(stroke
				(width 0.1524)
				(type default)
			)
			(layer "F.SilkS")
		)
		(fp_line
			(start 0.7874 0.4064)
			(end -0.7874 0.4064)
			(stroke
				(width 0.1524)
				(type default)
			)
			(layer "F.SilkS")
		)
		(fp_line
			(start -0.7874 0.4064)
			(end -0.7874 -0.4064)
			(stroke
				(width 0.1524)
				(type default)
			)
			(layer "F.SilkS")
		)
		(fp_poly
			(pts
				(xy -0.508 0.2794) (xy -0.508 0.2286) (xy -0.635 0.2286) (xy -0.635 -0.254) (xy -0.5334 -0.254)
				(xy -0.5334 -0.2794) (xy 0.5334 -0.2794) (xy 0.5334 -0.254) (xy 0.635 -0.254) (xy 0.635 0.254) (xy 0.5334 0.254)
				(xy 0.5334 0.2794)
			)
			(stroke
				(width 0)
				(type default)
			)
			(fill no)
			(layer "F.CrtYd")
		)
		(pad "1" smd rect
			(at 0.40005 0 90)
			(size 0.4572 0.508)
			(layers "F.Cu" "F.Mask" "F.Paste")
			(net "P3V3_NODE1")
		)
		(pad "2" smd rect
			(at -0.40005 0 90)
			(size 0.4572 0.508)
			(layers "F.Cu" "F.Mask" "F.Paste")
			(net "BMC_NODE1_JTAG_TRST")
		)
	)
	(footprint ""
		(layer "F.Cu")
		(at 130.0988 -50.8508 90)
		(property "Reference" "R1323"
			(at 16.9164 30.81147 90)
			(unlocked yes)
			(layer "F.SilkS")
			(effects
				(font
					(size 0.7874 0.5842)
					(thickness 0.1524)
				)
				(justify left)
			)
		)
		(property "Value" ""
			(at 0 0 90)
			(layer "F.Fab")
			(effects
				(font
					(size 1.27 1.27)
				)
			)
		)
		(duplicate_pad_numbers_are_jumpers no)
		(fp_line
			(start 0.7874 -0.4064)
			(end 0.7874 0.4064)
			(stroke
				(width 0.1524)
				(type default)
			)
			(layer "F.SilkS")
		)
		(fp_line
			(start -0.7874 -0.4064)
			(end 0.7874 -0.4064)
			(stroke
				(width 0.1524)
				(type default)
			)
			(layer "F.SilkS")
		)
		(fp_line
			(start 0.7874 0.4064)
			(end -0.7874 0.4064)
			(stroke
				(width 0.1524)
				(type default)
			)
			(layer "F.SilkS")
		)
		(fp_line
			(start -0.7874 0.4064)
			(end -0.7874 -0.4064)
			(stroke
				(width 0.1524)
				(type default)
			)
			(layer "F.SilkS")
		)
		(fp_poly
			(pts
				(xy -0.508 0.2794) (xy -0.508 0.2286) (xy -0.635 0.2286) (xy -0.635 -0.254) (xy -0.5334 -0.254)
				(xy -0.5334 -0.2794) (xy 0.5334 -0.2794) (xy 0.5334 -0.254) (xy 0.635 -0.254) (xy 0.635 0.254) (xy 0.5334 0.254)
				(xy 0.5334 0.2794)
			)
			(stroke
				(width 0)
				(type default)
			)
			(fill no)
			(layer "F.CrtYd")
		)
		(pad "1" smd rect
			(at 0.40005 0 90)
			(size 0.4572 0.508)
			(layers "F.Cu" "F.Mask" "F.Paste")
			(net "P5V_NODE1")
		)
		(pad "2" smd rect
			(at -0.40005 0 90)
			(size 0.4572 0.508)
			(layers "F.Cu" "F.Mask" "F.Paste")
			(net "UART_DSR_P4_N")
		)
	)
	(footprint ""
		(layer "F.Cu")
		(at 91.486228 -133.213094 -90)
		(property "Reference" "D38"
			(at -3.544316 0.760476 90)
			(unlocked yes)
			(layer "F.SilkS")
			(effects
				(font
					(size 0.7874 0.5842)
					(thickness 0.1524)
				)
				(justify left)
			)
		)
		(property "Value" ""
			(at 0 0 270)
			(layer "F.Fab")
			(effects
				(font
					(size 1.27 1.27)
				)
			)
		)
		(duplicate_pad_numbers_are_jumpers no)
		(fp_line
			(start -1.3208 0.5588)
			(end -1.3208 -0.5588)
			(stroke
				(width 0.1524)
				(type default)
			)
			(layer "F.SilkS")
		)
		(fp_line
			(start 1.3208 0.5588)
			(end -1.3208 0.5588)
			(stroke
				(width 0.1524)
				(type default)
			)
			(layer "F.SilkS")
		)
		(fp_line
			(start 1.6256 0.5588)
			(end 1.6256 -0.5588)
			(stroke
				(width 0.1524)
				(type default)
			)
			(layer "F.SilkS")
		)
		(fp_line
			(start 1.778 0.5588)
			(end 1.3208 0.5588)
			(stroke
				(width 0.1524)
				(type default)
			)
			(layer "F.SilkS")
		)
		(fp_line
			(start -1.3208 -0.5588)
			(end 1.3208 -0.5588)
			(stroke
				(width 0.1524)
				(type default)
			)
			(layer "F.SilkS")
		)
		(fp_line
			(start 1.3208 -0.5588)
			(end 1.3208 0.5588)
			(stroke
				(width 0.1524)
				(type default)
			)
			(layer "F.SilkS")
		)
		(fp_line
			(start 1.4732 -0.5588)
			(end 1.4732 0.5588)
			(stroke
				(width 0.1524)
				(type default)
			)
			(layer "F.SilkS")
		)
		(fp_line
			(start 1.778 -0.5588)
			(end 1.778 0.5588)
			(stroke
				(width 0.1524)
				(type default)
			)
			(layer "F.SilkS")
		)
		(fp_line
			(start 1.778 -0.5588)
			(end 1.3208 -0.5588)
			(stroke
				(width 0.1524)
				(type default)
			)
			(layer "F.SilkS")
		)
		(fp_circle
			(center 2.4384 0)
			(end 2.4384 -0.413512)
			(stroke
				(width 0.1524)
				(type default)
			)
			(fill no)
			(layer "F.SilkS")
		)
		(fp_rect
			(start -1.1684 0.508)
			(end 1.1684 -0.508)
			(stroke
				(width 0)
				(type default)
			)
			(fill no)
			(layer "F.CrtYd")
		)
		(fp_text user "-"
			(at 2.9464 0.28067 270)
			(unlocked yes)
			(layer "F.SilkS")
			(effects
				(font
					(size 0.7874 0.5842)
					(thickness 0.1524)
				)
				(justify left)
			)
		)
		(pad "A" smd rect
			(at -0.750062 0 270)
			(size 0.8128 0.8128)
			(layers "F.Cu" "F.Mask" "F.Paste")
			(net "P3V3_NODE1")
		)
		(pad "C" smd rect
			(at 0.750062 0 270)
			(size 0.8128 0.8128)
			(layers "F.Cu" "F.Mask" "F.Paste")
			(net "N53313596")
		)
	)
	(footprint ""
		(layer "F.Cu")
		(at 141.593316 -160.439608 -90)
		(property "Reference" "OSC6"
			(at 110.800896 66.176906 90)
			(unlocked yes)
			(layer "F.SilkS")
			(effects
				(font
					(size 0.7874 0.5842)
					(thickness 0.1524)
				)
				(justify left)
			)
		)
		(property "Value" ""
			(at 0 0 270)
			(layer "F.Fab")
			(effects
				(font
					(size 1.27 1.27)
				)
			)
		)
		(duplicate_pad_numbers_are_jumpers no)
		(fp_line
			(start -0.6096 2.936494)
			(end 2.35966 2.936494)
			(stroke
				(width 0.1524)
				(type default)
			)
			(layer "F.SilkS")
		)
		(fp_line
			(start 2.35966 2.936494)
			(end 2.35966 -0.7366)
			(stroke
				(width 0.1524)
				(type default)
			)
			(layer "F.SilkS")
		)
		(fp_line
			(start -0.6096 -0.7366)
			(end -0.6096 2.936494)
			(stroke
				(width 0.1524)
				(type default)
			)
			(layer "F.SilkS")
		)
		(fp_line
			(start 2.35966 -0.7366)
			(end -0.6096 -0.7366)
			(stroke
				(width 0.1524)
				(type default)
			)
			(layer "F.SilkS")
		)
		(fp_poly
			(pts
				(xy -1.761998 -0.40132) (xy -1.761998 -1.41732) (xy -0.745998 -0.90932)
			)
			(stroke
				(width 0)
				(type default)
			)
			(fill yes)
			(layer "F.SilkS")
		)
		(fp_poly
			(pts
				(xy -0.5334 -0.6604) (xy 0.5334 -0.6604) (xy 0.5334 -0.575056) (xy 1.21666 -0.575056) (xy 1.21666 -0.6604)
				(xy 2.28346 -0.6604) (xy 2.28346 0.6604) (xy 2.199894 0.6604) (xy 2.199894 1.539494) (xy 2.28346 1.539494)
				(xy 2.28346 2.860294) (xy 1.21666 2.860294) (xy 1.21666 2.77495) (xy 0.5334 2.77495) (xy 0.5334 2.860294)
				(xy -0.5334 2.860294) (xy -0.5334 1.539494) (xy -0.450088 1.539494) (xy -0.450088 0.6604) (xy -0.5334 0.6604)
			)
			(stroke
				(width 0)
				(type default)
			)
			(fill no)
			(layer "F.CrtYd")
		)
		(fp_line
			(start -0.450088 2.77495)
			(end 2.199894 2.77495)
			(stroke
				(width 0.1)
				(type default)
			)
			(layer "F.Fab")
		)
		(fp_line
			(start 2.199894 2.77495)
			(end 2.199894 -0.575056)
			(stroke
				(width 0.1)
				(type default)
			)
			(layer "F.Fab")
		)
		(fp_line
			(start -0.450088 -0.575056)
			(end -0.450088 2.77495)
			(stroke
				(width 0.1)
				(type default)
			)
			(layer "F.Fab")
		)
		(fp_line
			(start 2.199894 -0.575056)
			(end -0.450088 -0.575056)
			(stroke
				(width 0.1)
				(type default)
			)
			(layer "F.Fab")
		)
		(fp_poly
			(pts
				(xy -1.843278 0.508) (xy -1.843278 -0.508) (xy -0.827278 0)
			)
			(stroke
				(width 0)
				(type default)
			)
			(fill yes)
			(layer "F.Fab")
		)
		(pad "1" smd rect
			(at 0 0 270)
			(size 0.9652 1.2192)
			(layers "F.Cu" "F.Mask" "F.Paste")
			(net "N31521709")
		)
		(pad "2" smd rect
			(at 0 2.199894 270)
			(size 0.9652 1.2192)
			(layers "F.Cu" "F.Mask" "F.Paste")
			(net "GND")
		)
		(pad "3" smd rect
			(at 1.75006 2.199894 270)
			(size 0.9652 1.2192)
			(layers "F.Cu" "F.Mask" "F.Paste")
			(net "N31521711")
		)
		(pad "4" smd rect
			(at 1.75006 0 270)
			(size 0.9652 1.2192)
			(layers "F.Cu" "F.Mask" "F.Paste")
			(net "P3V3_NODE1")
		)
	)
)
